FILE_TYPE = MACRO_DRAWING;
SET COLOR_WIRE YELLOW;
SET COLOR_PROP ORANGE;
SET COLOR_DOT WHITE;
SET COLOR_ARC YELLOW;
SET COLOR_BODY GREEN;
SET COLOR_NOTE PURPLE;
SET PROP_DISPLAY VALUE;
SET PAGE_NUMBER P1;
FORCEADD QUANTA_TITLE_BLOCK_C..1
(-100 100);
FORCEPROP 1 LAST CUSTOM_TXT_CDS <NAME_2>
J 0
(-3275 150);
FORCEPROP 1 LAST CUSTOM_TXT_CDS <NAME_1>
J 0
(-3275 275);
FORCEPROP 1 LAST CUSTOM_TXT_CDS <Q_NUMBER>
J 0
(-1503 203);
DISPLAY 1.212766 (-1503 203);
FORCEPROP 1 LAST CUSTOM_TXT_CDS <Q_PROJ>
J 0
(-2482 202);
DISPLAY 1.212766 (-2482 202);
FORCEPROP 1 LAST CUSTOM_TXT_CDS <Q_REV>
J 0
(-284 203);
DISPLAY 1.212766 (-284 203);
FORCEPROP 1 LAST CUSTOM_TXT_CDS <CON_LAST_MODIFIED>
J 0
(-1985 115);
DISPLAY 0.978723 (-1985 115);
FORCEPROP 1 LAST CUSTOM_TXT_CDS <CON_PAGE_NUM> OF <CON_TOTAL_PAGES>
J 0
(-546 118);
DISPLAY 0.978723 (-546 118);
FORCEPROP 1 LAST Q_TITLE COVER PAGE
J 0
(-9400 150);
DISPLAY 2.446809 (-9400 150);
PAINT GREEN (-9400 150);
FORCEPROP 1 LAST Q_DEPT BU9
J 1
(-3863 149);
DISPLAY 1.957447 (-3863 149);
PAINT GREEN (-3863 149);
FORCEPROP 2 LAST PAGE_BORDER TRUE
J 0
(-7990 5350);
DISPLAY 0.638298 (-7990 5350);
PAINT PINK (-7990 5350);
DISPLAY INVISIBLE (-7990 5350);
FORCEPROP 1 LAST CDS_LMAN_SYM_OUTLINE -9475,6775,100,-125
J 0
(-100 100);
DISPLAY 0.468085 (-100 100);
PAINT GREEN (-100 100);
DISPLAY INVISIBLE (-100 100);
FORCEPROP 2 LAST CDS_LIB pure_quanta
J 0
(-100 100);
DISPLAY INVISIBLE (-100 100);
FORCEPROP 1 LAST COMMENT_BODY TRUE
J 0
(-88 87);
DISPLAY 0.978723 (-88 87);
PAINT GREEN (-88 87);
DISPLAY INVISIBLE (-88 87);
FORCEPROP 2 LAST CDS_XR_PAGE_TITLE CR-1 : @T6G_MB_LIB.T6G(SCH_1):PAGE1
J 0
(-7990 5350);
DISPLAY 0.638298 (-7990 5350);
PAINT PINK (-7990 5350);
DISPLAY INVISIBLE (-7990 5350);
FORCEPROP 2 LAST CUSTOM_TXT_CDS <XR_PAGE_TITLE>
J 0
(-7990 5350);
DISPLAY 0.638298 (-7990 5350);
PAINT PINK (-7990 5350);
DISPLAY INVISIBLE (-7990 5350);
FORCEPROP 0 LAST CDS_CON_LAST_MODIFIED Tue Mar 08 15:45:01 2022
J 0
(-1985 115);
DISPLAY INVISIBLE (-1985 115);
FORCENOTE
F0T MB WITH AMD CPU 
(-8325 4600) 0;
DISPLAY LEFT (-8325 4600);
DISPLAY 7.680851 (-8325 4600);
PAINT WHITE (-8325 4600);
FORCENOTE
PROJECT NAME:
(-7400 3025) 0;
DISPLAY LEFT (-7400 3025);
DISPLAY 4.872340 (-7400 3025);
PAINT WHITE (-7400 3025);
FORCENOTE
PCB NUMBER:
(-7400 2700) 0;
DISPLAY LEFT (-7400 2700);
DISPLAY 4.872340 (-7400 2700);
PAINT WHITE (-7400 2700);
FORCENOTE
DATE:2022/03/8
(-7425 1700) 0;
DISPLAY LEFT (-7425 1700);
DISPLAY 4.872340 (-7425 1700);
PAINT WHITE (-7425 1700);
FORCENOTE
REV:A
(-7400 2350) 0;
DISPLAY LEFT (-7400 2350);
DISPLAY 4.872340 (-7400 2350);
PAINT WHITE (-7400 2350);
FORCENOTE
PCBA:
(-7400 2025) 0;
DISPLAY LEFT (-7400 2025);
DISPLAY 4.872340 (-7400 2025);
PAINT WHITE (-7400 2025);
QUIT
